# BASEBOARD_FAB2 (Tioga Pass) — schematic netlist excerpt (pin names and nets, part order shuffled) for the footprints in the layout excerpt that follows; sources: Cadence DE-HDL packaged netlist, KiCad conversion of Wiwynn_Tioga_Pass_MB.brd

CT56  CAP  1000PF 50V 10% X7R  pkg 0402LF  page 210 : A = VR_PVSA_CPU1_PHASE_SW ; B = VR_PVSA_CPU1_PHASE_SW_RC
L1F1  IND-100NH-35-GP  pkg DISCRET-G8  page 225 : S = P12V_STBY ; F = VR_FET_SW_P12V_STBY_PVDDQ_GHJ
R10W2  RES  4.75K 1% CHIP  pkg 0402  page 251 : A = P3V3_STBY ; B = PUMP_TACH0

(kicad_pcb
	(version 20260206)
	(generator "pcbnew")
	(generator_version "10.0")
	(general
		(thickness 1.6)
		(legacy_teardrops no)
	)
	(paper "A4")
	(title_block
		(title "Wiwynn_Tioga_Pass_MB.brd")
		(comment 1 "Tioga Pass / footprints 1574-1576 of 4770")
	)
	(layers
		(0 "F.Cu" signal "TOP")
		(4 "In1.Cu" signal "L2GND")
		(6 "In2.Cu" signal "L3")
		(8 "In3.Cu" signal "L4GND")
		(10 "In4.Cu" signal "L5")
		(12 "In5.Cu" signal "L6GND")
		(14 "In6.Cu" signal "L7VCC")
		(16 "In7.Cu" signal "L8VCC")
		(18 "In8.Cu" signal "L9GND")
		(20 "In9.Cu" signal "L10")
		(22 "In10.Cu" signal "L11GND")
		(24 "In11.Cu" signal "L12")
		(26 "In12.Cu" signal "L13GND")
		(2 "B.Cu" signal "BOTTOM")
		(9 "F.Adhes" user "F.Adhesive")
		(11 "B.Adhes" user "B.Adhesive")
		(13 "F.Paste" user "Package Geometry/Pastemask Top")
		(15 "B.Paste" user "Package Geometry/Pastemask Bottom")
		(5 "F.SilkS" user "Ref Des/Silkscreen Top")
		(7 "B.SilkS" user "Ref Des/Silkscreen Bottom")
		(1 "F.Mask" user "Board Geometry/Soldermask Top")
		(3 "B.Mask" user "Board Geometry/Soldermask Bottom")
		(17 "Dwgs.User" user "User.Drawings")
		(19 "Cmts.User" user "User.Comments")
		(21 "Eco1.User" user "User.Eco1")
		(23 "Eco2.User" user "User.Eco2")
		(25 "Edge.Cuts" user "Board Geometry/Outline")
		(27 "Margin" user)
		(31 "F.CrtYd" user "Package Geometry/Place Bound Top")
		(29 "B.CrtYd" user "Package Geometry/Place Bound Bottom")
		(35 "F.Fab" user "Ref Des/Assembly Top")
		(33 "B.Fab" user "Ref Des/Assembly Bottom")
	)
	(footprint ""
		(layer "F.Cu")
		(at 38.40734 -93.8276 -90)
		(property "Reference" "CT56"
			(at -0.8382 -0.67818 270)
			(unlocked yes)
			(layer "F.SilkS")
			(effects
				(font
					(size 0.4064 0.254)
					(thickness 0.1524)
				)
				(justify left)
			)
		)
		(property "Value" ""
			(at 0 0 270)
			(layer "F.Fab")
			(effects
				(font
					(size 1.27 1.27)
				)
			)
		)
		(duplicate_pad_numbers_are_jumpers no)
		(fp_poly
			(pts
				(xy 0.3048 -0.1016) (xy 0.3048 0.9906) (xy -0.3048 0.9906) (xy -0.3048 -0.1016)
			)
			(stroke
				(width 0)
				(type default)
			)
			(fill no)
			(layer "F.CrtYd")
		)
		(fp_line
			(start -0.3048 0.9906)
			(end 0.3048 0.9906)
			(stroke
				(width 0.1)
				(type default)
			)
			(layer "F.Fab")
		)
		(fp_line
			(start 0.3048 0.9906)
			(end 0.3048 -0.1016)
			(stroke
				(width 0.1)
				(type default)
			)
			(layer "F.Fab")
		)
		(fp_line
			(start -0.3048 -0.1016)
			(end -0.3048 0.9906)
			(stroke
				(width 0.1)
				(type default)
			)
			(layer "F.Fab")
		)
		(fp_line
			(start 0.3048 -0.1016)
			(end -0.3048 -0.1016)
			(stroke
				(width 0.1)
				(type default)
			)
			(layer "F.Fab")
		)
		(pad "1" smd rect
			(at 0 0 270)
			(size 0.508 0.508)
			(layers "F.Cu" "F.Mask" "F.Paste")
			(net "VR_PVSA_CPU1_PHASE_SW")
		)
		(pad "2" smd rect
			(at 0 0.889 270)
			(size 0.508 0.508)
			(layers "F.Cu" "F.Mask" "F.Paste")
			(net "VR_PVSA_CPU1_PHASE_SW_RC")
		)
		(zone
			(layer "F.Cu")
			(hatch none 0.5)
			(connect_pads
				(clearance 0)
			)
			(min_thickness 0.25)
			(keepout
				(tracks not_allowed)
				(vias allowed)
				(pads allowed)
				(copperpour not_allowed)
				(footprints allowed)
			)
			(placement
				(enabled no)
				(sheetname "")
			)
			(fill
				(thermal_gap 0.5)
				(thermal_bridge_width 0.5)
				(island_removal_mode 0)
			)
			(polygon
				(pts
					(xy 37.77234 -94.0816) (xy 37.77234 -93.5736) (xy 38.15334 -93.5736) (xy 38.15334 -94.0816)
				)
			)
		)
		(zone
			(layer "F.Cu")
			(hatch none 0.5)
			(connect_pads
				(clearance 0)
			)
			(min_thickness 0.25)
			(keepout
				(tracks allowed)
				(vias not_allowed)
				(pads allowed)
				(copperpour not_allowed)
				(footprints allowed)
			)
			(placement
				(enabled no)
				(sheetname "")
			)
			(fill
				(thermal_gap 0.5)
				(thermal_bridge_width 0.5)
				(island_removal_mode 0)
			)
			(polygon
				(pts
					(xy 38.15334 -94.0816) (xy 38.15334 -93.5736) (xy 37.77234 -93.5736) (xy 37.77234 -94.0816)
				)
			)
		)
	)
	(footprint ""
		(layer "F.Cu")
		(at -3.405124 -16.925798)
		(property "Reference" "L1F1"
			(at 0 0 0)
			(layer "F.SilkS")
			(hide yes)
			(effects
				(font
					(size 1.27 1.27)
				)
			)
		)
		(property "Value" "*"
			(at -3.5941 0.3429 0)
			(unlocked yes)
			(layer "F.Fab")
			(hide yes)
			(effects
				(font
					(size 1.27 1.016)
					(thickness 0.1524)
				)
			)
		)
		(property "Device Type" "IND-100NH-35-GP_DISCRET-G8-INDA"
			(at -3.5941 -1.1811 0)
			(unlocked yes)
			(layer "F.Fab")
			(hide yes)
			(effects
				(font
					(size 1.27 1.016)
					(thickness 0.1524)
				)
			)
		)
		(duplicate_pad_numbers_are_jumpers no)
		(fp_line
			(start -2.2479 -2.794)
			(end 2.2479 -2.794)
			(stroke
				(width 0.1524)
				(type default)
			)
			(layer "F.SilkS")
		)
		(fp_line
			(start -2.2479 2.794)
			(end -2.2479 -2.794)
			(stroke
				(width 0.1524)
				(type default)
			)
			(layer "F.SilkS")
		)
		(fp_line
			(start 2.2479 -2.794)
			(end 2.2479 2.794)
			(stroke
				(width 0.1524)
				(type default)
			)
			(layer "F.SilkS")
		)
		(fp_line
			(start 2.2479 2.794)
			(end -2.2479 2.794)
			(stroke
				(width 0.1524)
				(type default)
			)
			(layer "F.SilkS")
		)
		(fp_rect
			(start -1.9939 1.9939)
			(end 1.9939 -1.9939)
			(stroke
				(width 0)
				(type default)
			)
			(fill no)
			(layer "F.CrtYd")
		)
		(fp_poly
			(pts
				(xy -2.5019 2.8702) (xy -2.5019 1.9939) (xy 1.9939 1.9939) (xy 1.9939 -1.9939) (xy -1.9939 -1.9939)
				(xy -1.9939 1.9812) (xy -2.5019 1.9812) (xy -2.5019 -2.8702) (xy 2.5019 -2.8702) (xy 2.5019 2.8702)
			)
			(stroke
				(width 0)
				(type default)
			)
			(fill no)
			(layer "F.CrtYd")
		)
		(fp_rect
			(start -2.5019 2.8702)
			(end 2.5019 -2.8702)
			(stroke
				(width 0)
				(type default)
			)
			(fill no)
			(layer "F.Fab")
		)
		(pad "1" smd rect
			(at 0 -1.745996)
			(size 1.5494 1.6002)
			(layers "F.Cu" "F.Mask" "F.Paste")
			(net "P12V_STBY")
		)
		(pad "2" smd rect
			(at 0 1.745996)
			(size 1.5494 1.6002)
			(layers "F.Cu" "F.Mask" "F.Paste")
			(net "VR_FET_SW_P12V_STBY_PVDDQ_GHJ")
		)
	)
	(footprint ""
		(layer "F.Cu")
		(at 436.499 -21.1455)
		(property "Reference" "R10W2"
			(at -0.8382 -0.67818 0)
			(unlocked yes)
			(layer "F.SilkS")
			(effects
				(font
					(size 0.4064 0.254)
					(thickness 0.1524)
				)
				(justify left)
			)
		)
		(property "Value" ""
			(at 0 0 0)
			(layer "F.Fab")
			(effects
				(font
					(size 1.27 1.27)
				)
			)
		)
		(duplicate_pad_numbers_are_jumpers no)
		(fp_poly
			(pts
				(xy -0.2794 -0.1016) (xy 0.2794 -0.1016) (xy 0.2794 0.9906) (xy -0.2794 0.9906)
			)
			(stroke
				(width 0)
				(type default)
			)
			(fill no)
			(layer "F.CrtYd")
		)
		(fp_line
			(start -0.2794 -0.1016)
			(end -0.2794 0.9906)
			(stroke
				(width 0.1)
				(type default)
			)
			(layer "F.Fab")
		)
		(fp_line
			(start -0.2794 0.9906)
			(end 0.2794 0.9906)
			(stroke
				(width 0.1)
				(type default)
			)
			(layer "F.Fab")
		)
		(fp_line
			(start 0.2794 -0.1016)
			(end -0.2794 -0.1016)
			(stroke
				(width 0.1)
				(type default)
			)
			(layer "F.Fab")
		)
		(fp_line
			(start 0.2794 0.9906)
			(end 0.2794 -0.1016)
			(stroke
				(width 0.1)
				(type default)
			)
			(layer "F.Fab")
		)
		(pad "1" smd rect
			(at 0 0)
			(size 0.508 0.508)
			(layers "F.Cu" "F.Mask" "F.Paste")
			(net "P3V3_STBY")
		)
		(pad "2" smd rect
			(at 0 0.889)
			(size 0.508 0.508)
			(layers "F.Cu" "F.Mask" "F.Paste")
			(net "PUMP_TACH0")
		)
		(zone
			(layer "F.Cu")
			(hatch none 0.5)
			(connect_pads
				(clearance 0)
			)
			(min_thickness 0.25)
			(keepout
				(tracks allowed)
				(vias not_allowed)
				(pads allowed)
				(copperpour not_allowed)
				(footprints allowed)
			)
			(placement
				(enabled no)
				(sheetname "")
			)
			(fill
				(thermal_gap 0.5)
				(thermal_bridge_width 0.5)
				(island_removal_mode 0)
			)
			(polygon
				(pts
					(xy 436.245 -20.8915) (xy 436.753 -20.8915) (xy 436.753 -20.5105) (xy 436.245 -20.5105)
				)
			)
		)
		(zone
			(layer "F.Cu")
			(hatch none 0.5)
			(connect_pads
				(clearance 0)
			)
			(min_thickness 0.25)
			(keepout
				(tracks not_allowed)
				(vias allowed)
				(pads allowed)
				(copperpour not_allowed)
				(footprints allowed)
			)
			(placement
				(enabled no)
				(sheetname "")
			)
			(fill
				(thermal_gap 0.5)
				(thermal_bridge_width 0.5)
				(island_removal_mode 0)
			)
			(polygon
				(pts
					(xy 436.245 -20.5105) (xy 436.753 -20.5105) (xy 436.753 -20.8915) (xy 436.245 -20.8915)
				)
			)
		)
	)
)
